(kicad_pcb
	(version 20241229)
	(generator "pcbnew")
	(generator_version "9.0")
	(general
		(thickness 1.62)
		(legacy_teardrops no)
	)
	(paper "A3")
	(title_block
		(title "COM Express 7 Baseboard")
		(date "2025-02-04")
		(rev "1.1.2")
		(company "Antmicro Ltd")
		(comment 1 "www.antmicro.com")
		(comment 9 "footprints 800-802 of 802")
	)
	(layers
		(0 "F.Cu" signal)
		(4 "In1.Cu" signal)
		(6 "In2.Cu" signal)
		(8 "In3.Cu" signal)
		(10 "In4.Cu" signal)
		(12 "In5.Cu" signal)
		(14 "In6.Cu" signal)
		(2 "B.Cu" signal)
		(9 "F.Adhes" user "F.Adhesive")
		(11 "B.Adhes" user "B.Adhesive")
		(13 "F.Paste" user)
		(15 "B.Paste" user)
		(5 "F.SilkS" user "F.Silkscreen")
		(7 "B.SilkS" user "B.Silkscreen")
		(1 "F.Mask" user)
		(3 "B.Mask" user)
		(17 "Dwgs.User" user "User.Drawings")
		(19 "Cmts.User" user "User.Comments")
		(21 "Eco1.User" user "User.Eco1")
		(23 "Eco2.User" user "User.Eco2")
		(25 "Edge.Cuts" user)
		(27 "Margin" user)
		(31 "F.CrtYd" user "F.Courtyard")
		(29 "B.CrtYd" user "B.Courtyard")
		(35 "F.Fab" user)
		(33 "B.Fab" user)
	)
	(footprint "antmicro-footprints:C_0603_1608Metric"
		(layer "B.Cu")
		(at 148.7 71.81 180)
		(descr "Capacitor SMD 0603")
		(tags "capacitor 0603")
		(property "Reference" "C79"
			(at -3.3 -0.5 0)
			(layer "B.SilkS")
			(effects
				(font
					(size 0.7 0.7)
					(thickness 0.15)
				)
				(justify left bottom mirror)
			)
		)
		(property "Value" "C_22u_16V_0603"
			(at -1.42757 -1.770288 0)
			(layer "B.Fab")
			(effects
				(font
					(size 0.7 0.7)
					(thickness 0.15)
				)
				(justify left bottom mirror)
			)
		)
		(property "Datasheet" "https://product.samsungsem.com/mlcc/CL10A226MO7JZN.do"
			(at 0 0 180)
			(layer "F.Fab")
			(hide yes)
			(effects
				(font
					(size 1.27 1.27)
					(thickness 0.15)
				)
			)
		)
		(property "Author" "Antmicro"
			(at 297.4 143.62 0)
			(layer "B.Fab")
			(hide yes)
			(effects
				(font
					(size 1 1)
					(thickness 0.15)
				)
				(justify mirror)
			)
		)
		(property "Dielectric" ""
			(at 297.4 143.62 0)
			(layer "B.Fab")
			(hide yes)
			(effects
				(font
					(size 1 1)
					(thickness 0.15)
				)
				(justify mirror)
			)
		)
		(property "License" "Apache-2.0"
			(at 297.4 143.62 0)
			(layer "B.Fab")
			(hide yes)
			(effects
				(font
					(size 1 1)
					(thickness 0.15)
				)
				(justify mirror)
			)
		)
		(property "MPN" "CL10A226MO7JZNC"
			(at 297.4 143.62 0)
			(layer "B.Fab")
			(hide yes)
			(effects
				(font
					(size 1 1)
					(thickness 0.15)
				)
				(justify mirror)
			)
		)
		(property "Manufacturer" "Samsung Electro-Mechanics"
			(at 297.4 143.62 0)
			(layer "B.Fab")
			(hide yes)
			(effects
				(font
					(size 1 1)
					(thickness 0.15)
				)
				(justify mirror)
			)
		)
		(property "Public" "False"
			(at 297.4 143.62 0)
			(layer "B.Fab")
			(hide yes)
			(effects
				(font
					(size 1 1)
					(thickness 0.15)
				)
				(justify mirror)
			)
		)
		(property "Val" "22u"
			(at 297.4 143.62 0)
			(layer "B.Fab")
			(hide yes)
			(effects
				(font
					(size 1 1)
					(thickness 0.15)
				)
				(justify mirror)
			)
		)
		(property "Voltage" "16V"
			(at 297.4 143.62 0)
			(layer "B.Fab")
			(hide yes)
			(effects
				(font
					(size 1 1)
					(thickness 0.15)
				)
				(justify mirror)
			)
		)
		(sheetname "M.2 key E")
		(sheetfile "m2keye.kicad_sch")
		(attr smd)
		(fp_line
			(start 0.15 0.4)
			(end -0.15 0.4)
			(stroke
				(width 0.15)
				(type solid)
			)
			(layer "B.SilkS")
		)
		(fp_line
			(start 0.15 -0.4)
			(end -0.15 -0.4)
			(stroke
				(width 0.15)
				(type solid)
			)
			(layer "B.SilkS")
		)
		(fp_rect
			(start -1.25 0.65)
			(end 1.25 -0.65)
			(stroke
				(width 0.05)
				(type solid)
			)
			(fill no)
			(layer "B.CrtYd")
		)
		(fp_rect
			(start -0.8 0.4)
			(end 0.8 -0.4)
			(stroke
				(width 0.15)
				(type solid)
			)
			(fill no)
			(layer "B.Fab")
		)
		(pad "1" smd roundrect
			(at -0.7 0 180)
			(size 0.8 1)
			(layers "B.Cu" "B.Mask" "B.Paste")
			(roundrect_rratio 0.2)
			(net 1 "GND")
			(pintype "passive")
			(teardrops
				(best_length_ratio 0.2)
				(max_length 1)
				(best_width_ratio 0.9)
				(max_width 2)
				(curved_edges yes)
				(filter_ratio 0.9)
				(enabled yes)
				(allow_two_segments yes)
				(prefer_zone_connections yes)
			)
		)
		(pad "2" smd roundrect
			(at 0.7 0 180)
			(size 0.8 1)
			(layers "B.Cu" "B.Mask" "B.Paste")
			(roundrect_rratio 0.2)
			(net 2 "+3V3")
			(pintype "passive")
			(teardrops
				(best_length_ratio 0.2)
				(max_length 1)
				(best_width_ratio 0.9)
				(max_width 2)
				(curved_edges yes)
				(filter_ratio 0.9)
				(enabled yes)
				(allow_two_segments yes)
				(prefer_zone_connections yes)
			)
		)
	)
	(footprint "antmicro-footprints:C_0603_1608Metric"
		(layer "B.Cu")
		(at 116.9 87.11)
		(descr "Capacitor SMD 0603")
		(tags "capacitor 0603")
		(property "Reference" "C20"
			(at -1.1 1.55 0)
			(layer "B.SilkS")
			(effects
				(font
					(size 0.7 0.7)
					(thickness 0.15)
				)
				(justify right bottom mirror)
			)
		)
		(property "Value" "C_22u_16V_0603"
			(at -1.42757 -1.770288 0)
			(layer "B.Fab")
			(effects
				(font
					(size 0.7 0.7)
					(thickness 0.15)
				)
				(justify right bottom mirror)
			)
		)
		(property "Datasheet" "https://product.samsungsem.com/mlcc/CL10A226MO7JZN.do"
			(at 0 0 0)
			(layer "F.Fab")
			(hide yes)
			(effects
				(font
					(size 1.27 1.27)
					(thickness 0.15)
				)
			)
		)
		(property "Author" "Antmicro"
			(at 0 0 0)
			(layer "B.Fab")
			(hide yes)
			(effects
				(font
					(size 1 1)
					(thickness 0.15)
				)
				(justify mirror)
			)
		)
		(property "Dielectric" ""
			(at 0 0 0)
			(layer "B.Fab")
			(hide yes)
			(effects
				(font
					(size 1 1)
					(thickness 0.15)
				)
				(justify mirror)
			)
		)
		(property "License" "Apache-2.0"
			(at 0 0 0)
			(layer "B.Fab")
			(hide yes)
			(effects
				(font
					(size 1 1)
					(thickness 0.15)
				)
				(justify mirror)
			)
		)
		(property "MPN" "CL10A226MO7JZNC"
			(at 0 0 0)
			(layer "B.Fab")
			(hide yes)
			(effects
				(font
					(size 1 1)
					(thickness 0.15)
				)
				(justify mirror)
			)
		)
		(property "Manufacturer" "Samsung Electro-Mechanics"
			(at 0 0 0)
			(layer "B.Fab")
			(hide yes)
			(effects
				(font
					(size 1 1)
					(thickness 0.15)
				)
				(justify mirror)
			)
		)
		(property "Public" "False"
			(at 0 0 0)
			(layer "B.Fab")
			(hide yes)
			(effects
				(font
					(size 1 1)
					(thickness 0.15)
				)
				(justify mirror)
			)
		)
		(property "Val" "22u"
			(at 0 0 0)
			(layer "B.Fab")
			(hide yes)
			(effects
				(font
					(size 1 1)
					(thickness 0.15)
				)
				(justify mirror)
			)
		)
		(property "Voltage" "16V"
			(at 0 0 0)
			(layer "B.Fab")
			(hide yes)
			(effects
				(font
					(size 1 1)
					(thickness 0.15)
				)
				(justify mirror)
			)
		)
		(sheetname "2xUSB3.0+RJ45")
		(sheetfile "usb3+rj45.kicad_sch")
		(attr smd)
		(fp_line
			(start 0.15 -0.4)
			(end -0.15 -0.4)
			(stroke
				(width 0.15)
				(type solid)
			)
			(layer "B.SilkS")
		)
		(fp_line
			(start 0.15 0.4)
			(end -0.15 0.4)
			(stroke
				(width 0.15)
				(type solid)
			)
			(layer "B.SilkS")
		)
		(fp_rect
			(start -1.25 0.65)
			(end 1.25 -0.65)
			(stroke
				(width 0.05)
				(type solid)
			)
			(fill no)
			(layer "B.CrtYd")
		)
		(fp_rect
			(start -0.8 0.4)
			(end 0.8 -0.4)
			(stroke
				(width 0.15)
				(type solid)
			)
			(fill no)
			(layer "B.Fab")
		)
		(pad "1" smd roundrect
			(at -0.7 0)
			(size 0.8 1)
			(layers "B.Cu" "B.Mask" "B.Paste")
			(roundrect_rratio 0.2)
			(net 1 "GND")
			(pintype "passive")
			(teardrops
				(best_length_ratio 0.2)
				(max_length 1)
				(best_width_ratio 0.9)
				(max_width 2)
				(curved_edges yes)
				(filter_ratio 0.9)
				(enabled yes)
				(allow_two_segments yes)
				(prefer_zone_connections yes)
			)
		)
		(pad "2" smd roundrect
			(at 0.7 0)
			(size 0.8 1)
			(layers "B.Cu" "B.Mask" "B.Paste")
			(roundrect_rratio 0.2)
			(net 52 "+5V")
			(pintype "passive")
			(teardrops
				(best_length_ratio 0.2)
				(max_length 1)
				(best_width_ratio 0.9)
				(max_width 2)
				(curved_edges yes)
				(filter_ratio 0.9)
				(enabled yes)
				(allow_two_segments yes)
				(prefer_zone_connections yes)
			)
		)
	)
	(footprint "antmicro-footprints:TP_SMD_0.75mm"
		(layer "B.Cu")
		(at 258.95 84.41 180)
		(property "Reference" "TP15"
			(at 0.399999 -0.4 0)
			(layer "B.SilkS")
			(effects
				(font
					(size 0.7 0.7)
					(thickness 0.15)
				)
				(justify left bottom mirror)
			)
		)
		(property "Value" "TP_0.75mm_SMD"
			(at 0 -1.2 0)
			(layer "B.Fab")
			(effects
				(font
					(size 0.7 0.7)
					(thickness 0.15)
				)
				(justify left bottom mirror)
			)
		)
		(property "Author" "Antmicro"
			(at 517.9 168.82 0)
			(layer "B.Fab")
			(hide yes)
			(effects
				(font
					(size 1 1)
					(thickness 0.15)
				)
				(justify mirror)
			)
		)
		(property "License" "Apache-2.0"
			(at 517.9 168.82 0)
			(layer "B.Fab")
			(hide yes)
			(effects
				(font
					(size 1 1)
					(thickness 0.15)
				)
				(justify mirror)
			)
		)
		(property "MPN" ""
			(at 517.9 168.82 0)
			(layer "B.Fab")
			(hide yes)
			(effects
				(font
					(size 1 1)
					(thickness 0.15)
				)
				(justify mirror)
			)
		)
		(property "Manufacturer" ""
			(at 517.9 168.82 0)
			(layer "B.Fab")
			(hide yes)
			(effects
				(font
					(size 1 1)
					(thickness 0.15)
				)
				(justify mirror)
			)
		)
		(property "Public" "False"
			(at 517.9 168.82 0)
			(layer "B.Fab")
			(hide yes)
			(effects
				(font
					(size 1 1)
					(thickness 0.15)
				)
				(justify mirror)
			)
		)
		(sheetname "Misc")
		(sheetfile "misc.kicad_sch")
		(attr exclude_from_pos_files exclude_from_bom)
		(fp_circle
			(center 0 0)
			(end 0.475 0)
			(stroke
				(width 0.05)
				(type default)
			)
			(fill no)
			(layer "B.CrtYd")
		)
		(pad "1" smd circle
			(at 0 0 180)
			(size 0.75 0.75)
			(layers "B.Cu" "B.Mask")
			(net 707 "Net-(U24-TACH3)")
			(pinfunction "1")
			(pintype "passive")
			(teardrops
				(best_length_ratio 0.4)
				(max_length 1)
				(best_width_ratio 0.9)
				(max_width 2)
				(curved_edges yes)
				(filter_ratio 0.9)
				(enabled yes)
				(allow_two_segments yes)
				(prefer_zone_connections yes)
			)
		)
	)
)
